(kicad_pcb
	(version 20260206)
	(generator "pcbnew")
	(generator_version "10.0")
	(general
		(thickness 1.6)
		(legacy_teardrops no)
	)
	(paper "A4")
	(title_block
		(title "Bryce Canyon_F.DPB_16315-1-OCP.brd")
		(comment 1 "Bryce Canyon / footprint 448 of 2223 (MONO3), pads 147-166 of 166")
	)
	(layers
		(0 "F.Cu" signal "TOP")
		(4 "In1.Cu" signal "L2GND")
		(6 "In2.Cu" signal "L3")
		(8 "In3.Cu" signal "L4GND")
		(10 "In4.Cu" signal "L5")
		(12 "In5.Cu" signal "L6VCC")
		(14 "In6.Cu" signal "L7VCC")
		(16 "In7.Cu" signal "L8")
		(18 "In8.Cu" signal "L9GND")
		(20 "In9.Cu" signal "L10")
		(22 "In10.Cu" signal "L11GND")
		(2 "B.Cu" signal "BOTTOM")
		(9 "F.Adhes" user "F.Adhesive")
		(11 "B.Adhes" user "B.Adhesive")
		(13 "F.Paste" user "Package Geometry/Pastemask Top")
		(15 "B.Paste" user "Package Geometry/Pastemask Bottom")
		(5 "F.SilkS" user "Ref Des/Silkscreen Top")
		(7 "B.SilkS" user "Ref Des/Silkscreen Bottom")
		(1 "F.Mask" user "Board Geometry/Soldermask Top")
		(3 "B.Mask" user "Board Geometry/Soldermask Bottom")
		(17 "Dwgs.User" user "User.Drawings")
		(19 "Cmts.User" user "User.Comments")
		(21 "Eco1.User" user "User.Eco1")
		(23 "Eco2.User" user "User.Eco2")
		(25 "Edge.Cuts" user "Board Geometry/Outline")
		(27 "Margin" user)
		(31 "F.CrtYd" user "Package Geometry/Place Bound Top")
		(29 "B.CrtYd" user "Package Geometry/Place Bound Bottom")
		(35 "F.Fab" user "Ref Des/Assembly Top")
		(33 "B.Fab" user "Ref Des/Assembly Bottom")
	)
	(footprint ""
		(layer "F.Cu")
		(at 281.999944 -111.149892 90)
		(property "Reference" "MONO3"
			(at 0 0 90)
			(layer "F.SilkS")
			(hide yes)
			(effects
				(font
					(size 1.27 1.27)
				)
			)
		)
		(property "Value" "AMP-CONN164-4R-1-GP"
			(at -25.705054 -1.203706 90)
			(unlocked yes)
			(layer "F.Fab")
			(hide yes)
			(effects
				(font
					(size 1.016 1.016)
					(thickness 0.1524)
				)
			)
		)
		(property "Device Type" "PREFIT-164P-890091-1H441"
			(at -25.705054 -2.727706 90)
			(unlocked yes)
			(layer "F.Fab")
			(hide yes)
			(effects
				(font
					(size 1.016 1.016)
					(thickness 0.1524)
				)
			)
		)
		(duplicate_pad_numbers_are_jumpers no)
		(pad "B63" thru_hole circle
			(at 52.349908 1.249934 90)
			(size 1.0668 1.0668)
			(drill 0.719836)
			(layers "*.Cu" "*.Mask")
			(remove_unused_layers no)
			(net "PCIE_COMP_B_TO_SCC_B_7_DP")
			(clearance 0.1905)
			(thermal_gap 0.1905)
		)
		(pad "B64" thru_hole circle
			(at 53.349906 3.24993 90)
			(size 1.0668 1.0668)
			(drill 0.719836)
			(layers "*.Cu" "*.Mask")
			(remove_unused_layers no)
			(net "PCIE_COMP_B_TO_SCC_B_7_DN")
			(clearance 0.1905)
			(thermal_gap 0.1905)
		)
		(pad "B65" thru_hole circle
			(at 54.349904 1.249934 90)
			(size 1.0668 1.0668)
			(drill 0.719836)
			(layers "*.Cu" "*.Mask")
			(remove_unused_layers no)
			(net "GND")
			(clearance 0.1905)
			(thermal_gap 0.1905)
		)
		(pad "B66" thru_hole circle
			(at 55.349902 3.24993 90)
			(size 1.0668 1.0668)
			(drill 0.719836)
			(layers "*.Cu" "*.Mask")
			(remove_unused_layers no)
			(net "GND")
			(clearance 0.1905)
			(thermal_gap 0.1905)
		)
		(pad "B67" thru_hole circle
			(at 56.3499 1.249934 90)
			(size 1.0668 1.0668)
			(drill 0.719836)
			(layers "*.Cu" "*.Mask")
			(remove_unused_layers no)
			(net "PCIE_COMP_B_TO_IOM_B_8_DP")
			(clearance 0.1905)
			(thermal_gap 0.1905)
		)
		(pad "B68" thru_hole circle
			(at 57.349898 3.24993 90)
			(size 1.0668 1.0668)
			(drill 0.719836)
			(layers "*.Cu" "*.Mask")
			(remove_unused_layers no)
			(net "PCIE_COMP_B_TO_IOM_B_8_DN")
			(clearance 0.1905)
			(thermal_gap 0.1905)
		)
		(pad "B69" thru_hole circle
			(at 58.349896 1.249934 90)
			(size 1.0668 1.0668)
			(drill 0.719836)
			(layers "*.Cu" "*.Mask")
			(remove_unused_layers no)
			(net "GND")
			(clearance 0.1905)
			(thermal_gap 0.1905)
		)
		(pad "B70" thru_hole circle
			(at 59.349894 3.24993 90)
			(size 1.0668 1.0668)
			(drill 0.719836)
			(layers "*.Cu" "*.Mask")
			(remove_unused_layers no)
			(net "GND")
			(clearance 0.1905)
			(thermal_gap 0.1905)
		)
		(pad "B71" thru_hole circle
			(at 60.349892 1.249934 90)
			(size 1.0668 1.0668)
			(drill 0.719836)
			(layers "*.Cu" "*.Mask")
			(remove_unused_layers no)
			(net "PCIE_COMP_B_TO_IOM_B_9_DP")
			(clearance 0.1905)
			(thermal_gap 0.1905)
		)
		(pad "B72" thru_hole circle
			(at 61.34989 3.24993 90)
			(size 1.0668 1.0668)
			(drill 0.719836)
			(layers "*.Cu" "*.Mask")
			(remove_unused_layers no)
			(net "PCIE_COMP_B_TO_IOM_B_9_DN")
			(clearance 0.1905)
			(thermal_gap 0.1905)
		)
		(pad "B73" thru_hole circle
			(at 62.349888 1.249934 90)
			(size 1.0668 1.0668)
			(drill 0.719836)
			(layers "*.Cu" "*.Mask")
			(remove_unused_layers no)
			(net "GND")
			(clearance 0.1905)
			(thermal_gap 0.1905)
		)
		(pad "B74" thru_hole circle
			(at 63.349886 3.24993 90)
			(size 1.0668 1.0668)
			(drill 0.719836)
			(layers "*.Cu" "*.Mask")
			(remove_unused_layers no)
			(net "GND")
			(clearance 0.1905)
			(thermal_gap 0.1905)
		)
		(pad "B75" thru_hole circle
			(at 64.349884 1.249934 90)
			(size 1.0668 1.0668)
			(drill 0.719836)
			(layers "*.Cu" "*.Mask")
			(remove_unused_layers no)
			(net "PCIE_COMP_B_TO_IOM_B_10_DP")
			(clearance 0.1905)
			(thermal_gap 0.1905)
		)
		(pad "B76" thru_hole circle
			(at 65.349882 3.24993 90)
			(size 1.0668 1.0668)
			(drill 0.719836)
			(layers "*.Cu" "*.Mask")
			(remove_unused_layers no)
			(net "PCIE_COMP_B_TO_IOM_B_10_DN")
			(clearance 0.1905)
			(thermal_gap 0.1905)
		)
		(pad "B77" thru_hole circle
			(at 66.34988 1.249934 90)
			(size 1.0668 1.0668)
			(drill 0.719836)
			(layers "*.Cu" "*.Mask")
			(remove_unused_layers no)
			(net "GND")
			(clearance 0.1905)
			(thermal_gap 0.1905)
		)
		(pad "B78" thru_hole circle
			(at 67.349878 3.24993 90)
			(size 1.0668 1.0668)
			(drill 0.719836)
			(layers "*.Cu" "*.Mask")
			(remove_unused_layers no)
			(net "GND")
			(clearance 0.1905)
			(thermal_gap 0.1905)
		)
		(pad "B79" thru_hole circle
			(at 68.349876 1.249934 90)
			(size 1.0668 1.0668)
			(drill 0.719836)
			(layers "*.Cu" "*.Mask")
			(remove_unused_layers no)
			(net "PCIE_COMP_B_TO_IOM_B_11_DP")
			(clearance 0.1905)
			(thermal_gap 0.1905)
		)
		(pad "B80" thru_hole circle
			(at 69.349874 3.24993 90)
			(size 1.0668 1.0668)
			(drill 0.719836)
			(layers "*.Cu" "*.Mask")
			(remove_unused_layers no)
			(net "PCIE_COMP_B_TO_IOM_B_11_DN")
			(clearance 0.1905)
			(thermal_gap 0.1905)
		)
		(pad "B81" thru_hole circle
			(at 70.350126 1.249934 90)
			(size 1.0668 1.0668)
			(drill 0.719836)
			(layers "*.Cu" "*.Mask")
			(remove_unused_layers no)
			(net "GND")
			(clearance 0.1905)
			(thermal_gap 0.1905)
		)
		(pad "B82" thru_hole circle
			(at 71.350124 3.24993 90)
			(size 1.0668 1.0668)
			(drill 0.719836)
			(layers "*.Cu" "*.Mask")
			(remove_unused_layers no)
			(net "GND")
			(clearance 0.1905)
			(thermal_gap 0.1905)
		)
	)
)
